(kicad_pcb
	(version 20260206)
	(generator "pcbnew")
	(generator_version "10.0")
	(general
		(thickness 1.6)
		(legacy_teardrops no)
	)
	(paper "A4")
	(title_block
		(title "Bryce Canyon_Front Panel_16369-1_OCP.brd")
		(comment 1 "Bryce Canyon / footprints 22-28 of 154")
	)
	(layers
		(0 "F.Cu" signal "TOP")
		(4 "In1.Cu" signal "L2GND")
		(6 "In2.Cu" signal "L3VCC")
		(2 "B.Cu" signal "BOTTOM")
		(9 "F.Adhes" user "F.Adhesive")
		(11 "B.Adhes" user "B.Adhesive")
		(13 "F.Paste" user "Package Geometry/Pastemask Top")
		(15 "B.Paste" user "Package Geometry/Pastemask Bottom")
		(5 "F.SilkS" user "Ref Des/Silkscreen Top")
		(7 "B.SilkS" user "Ref Des/Silkscreen Bottom")
		(1 "F.Mask" user "Board Geometry/Soldermask Top")
		(3 "B.Mask" user "Board Geometry/Soldermask Bottom")
		(17 "Dwgs.User" user "User.Drawings")
		(19 "Cmts.User" user "User.Comments")
		(21 "Eco1.User" user "User.Eco1")
		(23 "Eco2.User" user "User.Eco2")
		(25 "Edge.Cuts" user "Board Geometry/Outline")
		(27 "Margin" user)
		(31 "F.CrtYd" user "Package Geometry/Place Bound Top")
		(29 "B.CrtYd" user "Package Geometry/Place Bound Bottom")
		(35 "F.Fab" user "Ref Des/Assembly Top")
		(33 "B.Fab" user "Ref Des/Assembly Bottom")
	)
	(footprint ""
		(layer "F.Cu")
		(at 7.747 -70.358 -90)
		(property "Reference" "C16"
			(at 0 0 270)
			(layer "F.SilkS")
			(hide yes)
			(effects
				(font
					(size 1.27 1.27)
				)
			)
		)
		(property "Value" "SC1000P2KV6KX-GP-U"
			(at 0.0508 -3.5052 270)
			(unlocked yes)
			(layer "F.Fab")
			(hide yes)
			(effects
				(font
					(size 1.016 1.016)
					(thickness 0.1524)
				)
			)
		)
		(property "Device Type" "C1206H58"
			(at 0.0508 -5.0292 270)
			(unlocked yes)
			(layer "F.Fab")
			(hide yes)
			(effects
				(font
					(size 1.016 1.016)
					(thickness 0.1524)
				)
			)
		)
		(duplicate_pad_numbers_are_jumpers no)
		(fp_line
			(start -1.016 2.2352)
			(end -1.016 0.8128)
			(stroke
				(width 0.1524)
				(type default)
			)
			(layer "F.SilkS")
		)
		(fp_line
			(start 1.016 2.2352)
			(end -1.016 2.2352)
			(stroke
				(width 0.1524)
				(type default)
			)
			(layer "F.SilkS")
		)
		(fp_line
			(start 1.016 0.8382)
			(end 1.016 2.2352)
			(stroke
				(width 0.1524)
				(type default)
			)
			(layer "F.SilkS")
		)
		(fp_line
			(start -1.016 -2.2352)
			(end -1.016 -0.8382)
			(stroke
				(width 0.1524)
				(type default)
			)
			(layer "F.SilkS")
		)
		(fp_line
			(start 1.016 -2.2352)
			(end 1.016 -0.8382)
			(stroke
				(width 0.1524)
				(type default)
			)
			(layer "F.SilkS")
		)
		(fp_line
			(start 1.016 -2.2352)
			(end -1.016 -2.2352)
			(stroke
				(width 0.1524)
				(type default)
			)
			(layer "F.SilkS")
		)
		(fp_rect
			(start -1.0922 2.3114)
			(end 1.0922 -2.3114)
			(stroke
				(width 0)
				(type default)
			)
			(fill no)
			(layer "F.CrtYd")
		)
		(fp_poly
			(pts
				(xy -1.0922 -2.3114) (xy 1.0922 -2.3114) (xy 1.0922 2.3114) (xy -1.0922 2.3114)
			)
			(stroke
				(width 0)
				(type default)
			)
			(fill no)
			(layer "F.Fab")
		)
		(pad "1" smd rect
			(at 0 -1.397 270)
			(size 1.651 1.27)
			(layers "F.Cu" "F.Mask" "F.Paste")
			(net "USB_CONN_A_GND")
		)
		(pad "2" smd rect
			(at 0 1.397 270)
			(size 1.651 1.27)
			(layers "F.Cu" "F.Mask" "F.Paste")
			(net "GND")
		)
	)
	(footprint ""
		(layer "F.Cu")
		(at 49.696116 -72.650096 180)
		(property "Reference" "C7"
			(at 0 0 180)
			(layer "F.SilkS")
			(hide yes)
			(effects
				(font
					(size 1.27 1.27)
				)
			)
		)
		(property "Value" "SC1U16V3KX-5GP"
			(at 0 -3.5052 180)
			(unlocked yes)
			(layer "F.Fab")
			(hide yes)
			(effects
				(font
					(size 2.54 2.54)
					(thickness 0.381)
				)
			)
		)
		(property "Device Type" "C603H36"
			(at 0 -5.0292 180)
			(unlocked yes)
			(layer "F.Fab")
			(hide yes)
			(effects
				(font
					(size 2.54 2.54)
					(thickness 0.381)
				)
			)
		)
		(duplicate_pad_numbers_are_jumpers no)
		(fp_line
			(start 0.508 0)
			(end -0.508 0)
			(stroke
				(width 0.2032)
				(type default)
			)
			(layer "F.SilkS")
		)
		(fp_rect
			(start -0.5842 1.3335)
			(end 0.5842 -1.3335)
			(stroke
				(width 0)
				(type default)
			)
			(fill no)
			(layer "F.CrtYd")
		)
		(fp_rect
			(start -0.5842 1.3335)
			(end 0.5842 -1.3335)
			(stroke
				(width 0)
				(type default)
			)
			(fill no)
			(layer "F.Fab")
		)
		(pad "1" smd custom
			(at 0 -0.762 180)
			(size 0.2159 0.2159)
			(layers "F.Cu" "F.Mask" "F.Paste")
			(net "P5V_USB_B")
			(options
				(clearance outline)
				(anchor circle)
			)
			(primitives
				(gr_poly
					(pts
						(arc
							(start -0.3302 -0.4318)
							(mid -0.402042 -0.402042)
							(end -0.4318 -0.3302)
						)
						(arc
							(start -0.4318 0.3302)
							(mid -0.402042 0.402042)
							(end -0.3302 0.4318)
						)
						(arc
							(start 0.3302 0.4318)
							(mid 0.402042 0.402042)
							(end 0.4318 0.3302)
						)
						(arc
							(start 0.4318 -0.3302)
							(mid 0.402042 -0.402042)
							(end 0.3302 -0.4318)
						)
					)
					(width 0)
					(fill yes)
				)
			)
		)
		(pad "2" smd custom
			(at 0 0.762 180)
			(size 0.2159 0.2159)
			(layers "F.Cu" "F.Mask" "F.Paste")
			(net "GND")
			(options
				(clearance outline)
				(anchor circle)
			)
			(primitives
				(gr_poly
					(pts
						(arc
							(start -0.3302 -0.4318)
							(mid -0.402042 -0.402042)
							(end -0.4318 -0.3302)
						)
						(arc
							(start -0.4318 0.3302)
							(mid -0.402042 0.402042)
							(end -0.3302 0.4318)
						)
						(arc
							(start 0.3302 0.4318)
							(mid 0.402042 0.402042)
							(end 0.4318 0.3302)
						)
						(arc
							(start 0.4318 -0.3302)
							(mid 0.402042 -0.402042)
							(end 0.3302 -0.4318)
						)
					)
					(width 0)
					(fill yes)
				)
			)
		)
	)
	(footprint ""
		(layer "F.Cu")
		(at 55.583328 -32.145986)
		(property "Reference" "R53"
			(at 0 0 0)
			(layer "F.SilkS")
			(hide yes)
			(effects
				(font
					(size 1.27 1.27)
				)
			)
		)
		(property "Value" "4K7R2F-GP"
			(at 0.064008 -4.679696 0)
			(unlocked yes)
			(layer "F.Fab")
			(hide yes)
			(effects
				(font
					(size 2.54 2.54)
					(thickness 0.381)
				)
			)
		)
		(property "Device Type" "R402H16"
			(at 0.064008 -6.203696 0)
			(unlocked yes)
			(layer "F.Fab")
			(hide yes)
			(effects
				(font
					(size 2.54 2.54)
					(thickness 0.381)
				)
			)
		)
		(duplicate_pad_numbers_are_jumpers no)
		(fp_line
			(start -0.508 -0.9398)
			(end -0.508 0.9398)
			(stroke
				(width 0.1524)
				(type default)
			)
			(layer "F.SilkS")
		)
		(fp_line
			(start 0.508 -0.9398)
			(end -0.508 -0.9398)
			(stroke
				(width 0.1524)
				(type default)
			)
			(layer "F.SilkS")
		)
		(fp_rect
			(start -0.508 0.9398)
			(end 0.508 -0.9398)
			(stroke
				(width 0)
				(type default)
			)
			(fill no)
			(layer "F.CrtYd")
		)
		(fp_rect
			(start -0.508 0.9398)
			(end 0.508 -0.9398)
			(stroke
				(width 0)
				(type default)
			)
			(fill no)
			(layer "F.Fab")
		)
		(pad "1" smd custom
			(at 0 -0.4445)
			(size 0.1397 0.1397)
			(layers "F.Cu" "F.Mask" "F.Paste")
			(net "P3V3_STBY_B")
			(options
				(clearance outline)
				(anchor circle)
			)
			(primitives
				(gr_poly
					(pts
						(arc
							(start -0.1778 -0.2794)
							(mid -0.249642 -0.249642)
							(end -0.2794 -0.1778)
						)
						(arc
							(start -0.2794 0.1778)
							(mid -0.249642 0.249642)
							(end -0.1778 0.2794)
						)
						(arc
							(start 0.1778 0.2794)
							(mid 0.249642 0.249642)
							(end 0.2794 0.1778)
						)
						(arc
							(start 0.2794 -0.1778)
							(mid 0.249642 -0.249642)
							(end 0.1778 -0.2794)
						)
					)
					(width 0)
					(fill yes)
				)
			)
		)
		(pad "2" smd custom
			(at 0 0.4445)
			(size 0.1397 0.1397)
			(layers "F.Cu" "F.Mask" "F.Paste")
			(net "RST_B_TS")
			(options
				(clearance outline)
				(anchor circle)
			)
			(primitives
				(gr_poly
					(pts
						(arc
							(start -0.1778 -0.2794)
							(mid -0.249642 -0.249642)
							(end -0.2794 -0.1778)
						)
						(arc
							(start -0.2794 0.1778)
							(mid -0.249642 0.249642)
							(end -0.1778 0.2794)
						)
						(arc
							(start 0.1778 0.2794)
							(mid 0.249642 0.249642)
							(end 0.2794 0.1778)
						)
						(arc
							(start 0.2794 -0.1778)
							(mid 0.249642 -0.249642)
							(end 0.1778 -0.2794)
						)
					)
					(width 0)
					(fill yes)
				)
			)
		)
	)
	(footprint ""
		(layer "F.Cu")
		(at 8.199882 -43.999912 90)
		(property "Reference" "LED1"
			(at 0 0 90)
			(layer "F.SilkS")
			(hide yes)
			(effects
				(font
					(size 1.27 1.27)
				)
			)
		)
		(property "Value" "LED-Y-167-GP"
			(at 3.3274 -0.4572 90)
			(unlocked yes)
			(layer "F.Fab")
			(hide yes)
			(effects
				(font
					(size 1.016 1.016)
					(thickness 0.1524)
				)
			)
		)
		(property "Device Type" "LED-100-4035-1A2KH274"
			(at 3.3274 -1.9812 90)
			(unlocked yes)
			(layer "F.Fab")
			(hide yes)
			(effects
				(font
					(size 1.016 1.016)
					(thickness 0.1524)
				)
			)
		)
		(duplicate_pad_numbers_are_jumpers no)
		(fp_line
			(start 1.905 -0.254)
			(end 1.397 0.254)
			(stroke
				(width 0.1524)
				(type default)
			)
			(layer "F.SilkS")
		)
		(fp_line
			(start 1.397 -0.254)
			(end 1.397 -0.762)
			(stroke
				(width 0.1524)
				(type default)
			)
			(layer "F.SilkS")
		)
		(fp_line
			(start 0.889 -0.254)
			(end 1.905 -0.254)
			(stroke
				(width 0.1524)
				(type default)
			)
			(layer "F.SilkS")
		)
		(fp_line
			(start 1.397 0.254)
			(end 0.889 -0.254)
			(stroke
				(width 0.1524)
				(type default)
			)
			(layer "F.SilkS")
		)
		(fp_line
			(start 1.397 0.254)
			(end 1.397 0.762)
			(stroke
				(width 0.1524)
				(type default)
			)
			(layer "F.SilkS")
		)
		(fp_line
			(start 0.889 0.254)
			(end 1.905 0.254)
			(stroke
				(width 0.1524)
				(type default)
			)
			(layer "F.SilkS")
		)
		(fp_line
			(start 1.427988 1.7526)
			(end 0.685546 1.7526)
			(stroke
				(width 0.1524)
				(type default)
			)
			(layer "F.SilkS")
		)
		(fp_line
			(start -0.685546 1.7526)
			(end -1.427988 1.7526)
			(stroke
				(width 0.1524)
				(type default)
			)
			(layer "F.SilkS")
		)
		(fp_arc
			(start 0.685546 1.7526)
			(mid 0 2.108377)
			(end -0.685546 1.7526)
			(stroke
				(width 0.1524)
				(type default)
			)
			(layer "F.SilkS")
		)
		(fp_arc
			(start -1.427988 1.7526)
			(mid 0 -2.260698)
			(end 1.427988 1.7526)
			(stroke
				(width 0.1524)
				(type default)
			)
			(layer "F.SilkS")
		)
		(fp_circle
			(center 0 -1.27)
			(end 0 -0.3302)
			(stroke
				(width 0.3048)
				(type default)
			)
			(fill no)
			(layer "F.SilkS")
		)
		(fp_circle
			(center 0 1.27)
			(end 0 2.2098)
			(stroke
				(width 0.3048)
				(type default)
			)
			(fill no)
			(layer "F.SilkS")
		)
		(fp_poly
			(pts
				(arc
					(start -1.334516 1.4986)
					(mid 0 -2.006673)
					(end 1.334516 1.4986)
				)
			)
			(stroke
				(width 0)
				(type default)
			)
			(fill no)
			(layer "F.CrtYd")
		)
		(fp_poly
			(pts
				(arc
					(start 0.806704 2.0066)
					(mid 0 2.362406)
					(end -0.806704 2.0066)
				)
				(arc
					(start -1.515618 2.0066)
					(mid -1.123616 -2.249673)
					(end 2.5146 -0.00635)
				)
				(arc
					(start 2.006854 -0.00635)
					(mid -0.824269 -1.829777)
					(end -1.334516 1.498854)
				)
				(arc
					(start 1.334516 1.498854)
					(mid 1.829775 0.824269)
					(end 2.006854 0.00635)
				)
				(arc
					(start 2.5146 0.00635)
					(mid 2.249622 1.12359)
					(end 1.515618 2.0066)
				)
			)
			(stroke
				(width 0)
				(type default)
			)
			(fill no)
			(layer "F.CrtYd")
		)
		(fp_poly
			(pts
				(arc
					(start 0.806704 2.0066)
					(mid 0 2.362406)
					(end -0.806704 2.0066)
				)
				(arc
					(start -1.515618 2.0066)
					(mid 0 -2.514665)
					(end 1.515618 2.0066)
				)
			)
			(stroke
				(width 0)
				(type default)
			)
			(fill no)
			(layer "F.Fab")
		)
		(pad "1A" thru_hole circle
			(at 0 -1.27 90)
			(size 1.1684 1.1684)
			(drill 0.8128)
			(layers "*.Cu" "*.Mask")
			(remove_unused_layers no)
			(net "SYS_FAULT_A_R")
			(clearance 0.1778)
			(thermal_gap 0.1778)
		)
		(pad "2K" thru_hole circle
			(at 0 1.27 90)
			(size 1.1684 1.1684)
			(drill 0.8128)
			(layers "*.Cu" "*.Mask")
			(remove_unused_layers no)
			(net "FAULT_LED_A")
			(clearance 0.1778)
			(thermal_gap 0.1778)
		)
	)
	(footprint ""
		(layer "F.Cu")
		(at 12.7 -15.1638 -90)
		(property "Reference" "R7"
			(at 0 0 270)
			(layer "F.SilkS")
			(hide yes)
			(effects
				(font
					(size 1.27 1.27)
				)
			)
		)
		(property "Value" "0R2J-2-GP"
			(at 0.064008 -4.679696 270)
			(unlocked yes)
			(layer "F.Fab")
			(hide yes)
			(effects
				(font
					(size 2.54 2.54)
					(thickness 0.381)
				)
			)
		)
		(property "Device Type" "R402H16"
			(at 0.064008 -6.203696 270)
			(unlocked yes)
			(layer "F.Fab")
			(hide yes)
			(effects
				(font
					(size 2.54 2.54)
					(thickness 0.381)
				)
			)
		)
		(duplicate_pad_numbers_are_jumpers no)
		(fp_line
			(start -0.508 -0.9398)
			(end -0.508 0.9398)
			(stroke
				(width 0.1524)
				(type default)
			)
			(layer "F.SilkS")
		)
		(fp_line
			(start 0.508 -0.9398)
			(end -0.508 -0.9398)
			(stroke
				(width 0.1524)
				(type default)
			)
			(layer "F.SilkS")
		)
		(fp_rect
			(start -0.508 0.9398)
			(end 0.508 -0.9398)
			(stroke
				(width 0)
				(type default)
			)
			(fill no)
			(layer "F.CrtYd")
		)
		(fp_rect
			(start -0.508 0.9398)
			(end 0.508 -0.9398)
			(stroke
				(width 0)
				(type default)
			)
			(fill no)
			(layer "F.Fab")
		)
		(pad "1" smd custom
			(at 0 -0.4445 270)
			(size 0.1397 0.1397)
			(layers "F.Cu" "F.Mask" "F.Paste")
			(net "I2C_DEBUG_A_SCL_R")
			(options
				(clearance outline)
				(anchor circle)
			)
			(primitives
				(gr_poly
					(pts
						(arc
							(start -0.1778 -0.2794)
							(mid -0.249642 -0.249642)
							(end -0.2794 -0.1778)
						)
						(arc
							(start -0.2794 0.1778)
							(mid -0.249642 0.249642)
							(end -0.1778 0.2794)
						)
						(arc
							(start 0.1778 0.2794)
							(mid 0.249642 0.249642)
							(end 0.2794 0.1778)
						)
						(arc
							(start 0.2794 -0.1778)
							(mid 0.249642 -0.249642)
							(end 0.1778 -0.2794)
						)
					)
					(width 0)
					(fill yes)
				)
			)
		)
		(pad "2" smd custom
			(at 0 0.4445 270)
			(size 0.1397 0.1397)
			(layers "F.Cu" "F.Mask" "F.Paste")
			(net "I2C_DEBUG_A_SCL_L")
			(options
				(clearance outline)
				(anchor circle)
			)
			(primitives
				(gr_poly
					(pts
						(arc
							(start -0.1778 -0.2794)
							(mid -0.249642 -0.249642)
							(end -0.2794 -0.1778)
						)
						(arc
							(start -0.2794 0.1778)
							(mid -0.249642 0.249642)
							(end -0.1778 0.2794)
						)
						(arc
							(start 0.1778 0.2794)
							(mid 0.249642 0.249642)
							(end 0.2794 0.1778)
						)
						(arc
							(start 0.2794 -0.1778)
							(mid 0.249642 -0.249642)
							(end 0.1778 -0.2794)
						)
					)
					(width 0)
					(fill yes)
				)
			)
		)
	)
	(footprint ""
		(layer "F.Cu")
		(at 55.722012 -7.01167)
		(property "Reference" "R73"
			(at 0 0 0)
			(layer "F.SilkS")
			(hide yes)
			(effects
				(font
					(size 1.27 1.27)
				)
			)
		)
		(property "Value" "4K7R2F-GP"
			(at 0.064008 -3.993896 0)
			(unlocked yes)
			(layer "F.Fab")
			(hide yes)
			(effects
				(font
					(size 1.016 1.016)
					(thickness 0.1524)
				)
			)
		)
		(property "Device Type" "R402H16"
			(at 0.064008 -5.517896 0)
			(unlocked yes)
			(layer "F.Fab")
			(hide yes)
			(effects
				(font
					(size 1.016 1.016)
					(thickness 0.1524)
				)
			)
		)
		(duplicate_pad_numbers_are_jumpers no)
		(fp_line
			(start -0.508 -0.9398)
			(end -0.508 0.9398)
			(stroke
				(width 0.1524)
				(type default)
			)
			(layer "F.SilkS")
		)
		(fp_line
			(start 0.508 -0.9398)
			(end -0.508 -0.9398)
			(stroke
				(width 0.1524)
				(type default)
			)
			(layer "F.SilkS")
		)
		(fp_rect
			(start -0.508 0.9398)
			(end 0.508 -0.9398)
			(stroke
				(width 0)
				(type default)
			)
			(fill no)
			(layer "F.CrtYd")
		)
		(fp_rect
			(start -0.508 0.9398)
			(end 0.508 -0.9398)
			(stroke
				(width 0)
				(type default)
			)
			(fill no)
			(layer "F.Fab")
		)
		(pad "1" smd custom
			(at 0 -0.4445)
			(size 0.1397 0.1397)
			(layers "F.Cu" "F.Mask" "F.Paste")
			(net "TCA9555_B_A2")
			(options
				(clearance outline)
				(anchor circle)
			)
			(primitives
				(gr_poly
					(pts
						(arc
							(start -0.1778 -0.2794)
							(mid -0.249642 -0.249642)
							(end -0.2794 -0.1778)
						)
						(arc
							(start -0.2794 0.1778)
							(mid -0.249642 0.249642)
							(end -0.1778 0.2794)
						)
						(arc
							(start 0.1778 0.2794)
							(mid 0.249642 0.249642)
							(end 0.2794 0.1778)
						)
						(arc
							(start 0.2794 -0.1778)
							(mid 0.249642 -0.249642)
							(end 0.1778 -0.2794)
						)
					)
					(width 0)
					(fill yes)
				)
			)
		)
		(pad "2" smd custom
			(at 0 0.4445)
			(size 0.1397 0.1397)
			(layers "F.Cu" "F.Mask" "F.Paste")
			(net "GND")
			(options
				(clearance outline)
				(anchor circle)
			)
			(primitives
				(gr_poly
					(pts
						(arc
							(start -0.1778 -0.2794)
							(mid -0.249642 -0.249642)
							(end -0.2794 -0.1778)
						)
						(arc
							(start -0.2794 0.1778)
							(mid -0.249642 0.249642)
							(end -0.1778 0.2794)
						)
						(arc
							(start 0.1778 0.2794)
							(mid 0.249642 0.249642)
							(end 0.2794 0.1778)
						)
						(arc
							(start 0.2794 -0.1778)
							(mid 0.249642 -0.249642)
							(end 0.1778 -0.2794)
						)
					)
					(width 0)
					(fill yes)
				)
			)
		)
	)
	(footprint ""
		(layer "F.Cu")
		(at 9.913874 -17.984216 -90)
		(property "Reference" "R65"
			(at 0 0 270)
			(layer "F.SilkS")
			(hide yes)
			(effects
				(font
					(size 1.27 1.27)
				)
			)
		)
		(property "Value" "4K7R2F-GP"
			(at 0.064008 -3.993896 270)
			(unlocked yes)
			(layer "F.Fab")
			(hide yes)
			(effects
				(font
					(size 1.016 1.016)
					(thickness 0.1524)
				)
			)
		)
		(property "Device Type" "R402H16"
			(at 0.064008 -5.517896 270)
			(unlocked yes)
			(layer "F.Fab")
			(hide yes)
			(effects
				(font
					(size 1.016 1.016)
					(thickness 0.1524)
				)
			)
		)
		(duplicate_pad_numbers_are_jumpers no)
		(fp_line
			(start -0.508 -0.9398)
			(end -0.508 0.9398)
			(stroke
				(width 0.1524)
				(type default)
			)
			(layer "F.SilkS")
		)
		(fp_line
			(start 0.508 -0.9398)
			(end -0.508 -0.9398)
			(stroke
				(width 0.1524)
				(type default)
			)
			(layer "F.SilkS")
		)
		(fp_rect
			(start -0.508 0.9398)
			(end 0.508 -0.9398)
			(stroke
				(width 0)
				(type default)
			)
			(fill no)
			(layer "F.CrtYd")
		)
		(fp_rect
			(start -0.508 0.9398)
			(end 0.508 -0.9398)
			(stroke
				(width 0)
				(type default)
			)
			(fill no)
			(layer "F.Fab")
		)
		(pad "1" smd custom
			(at 0 -0.4445 270)
			(size 0.1397 0.1397)
			(layers "F.Cu" "F.Mask" "F.Paste")
			(net "TCA9555_A_A0")
			(options
				(clearance outline)
				(anchor circle)
			)
			(primitives
				(gr_poly
					(pts
						(arc
							(start -0.1778 -0.2794)
							(mid -0.249642 -0.249642)
							(end -0.2794 -0.1778)
						)
						(arc
							(start -0.2794 0.1778)
							(mid -0.249642 0.249642)
							(end -0.1778 0.2794)
						)
						(arc
							(start 0.1778 0.2794)
							(mid 0.249642 0.249642)
							(end 0.2794 0.1778)
						)
						(arc
							(start 0.2794 -0.1778)
							(mid 0.249642 -0.249642)
							(end 0.1778 -0.2794)
						)
					)
					(width 0)
					(fill yes)
				)
			)
		)
		(pad "2" smd custom
			(at 0 0.4445 270)
			(size 0.1397 0.1397)
			(layers "F.Cu" "F.Mask" "F.Paste")
			(net "GND")
			(options
				(clearance outline)
				(anchor circle)
			)
			(primitives
				(gr_poly
					(pts
						(arc
							(start -0.1778 -0.2794)
							(mid -0.249642 -0.249642)
							(end -0.2794 -0.1778)
						)
						(arc
							(start -0.2794 0.1778)
							(mid -0.249642 0.249642)
							(end -0.1778 0.2794)
						)
						(arc
							(start 0.1778 0.2794)
							(mid 0.249642 0.249642)
							(end 0.2794 0.1778)
						)
						(arc
							(start 0.2794 -0.1778)
							(mid 0.249642 -0.249642)
							(end 0.1778 -0.2794)
						)
					)
					(width 0)
					(fill yes)
				)
			)
		)
	)
)
